(kicad_pcb
	(version 20260206)
	(generator "pcbnew")
	(generator_version "10.0")
	(general
		(thickness 1.6)
		(legacy_teardrops no)
	)
	(paper "A4")
	(title_block
		(title "01162023_DA0F0TEBIF0_F0T_Expander_BD_F_brd_V02_OCP.brd")
		(comment 1 "Grand Teton / footprints 2600-2606 of 9728")
	)
	(layers
		(0 "F.Cu" signal "TOP")
		(4 "In1.Cu" signal "GND")
		(6 "In2.Cu" signal "VCC")
		(8 "In3.Cu" signal "VCC1")
		(10 "In4.Cu" signal "GND1")
		(12 "In5.Cu" signal "IN1")
		(14 "In6.Cu" signal "GND2")
		(16 "In7.Cu" signal "IN2")
		(18 "In8.Cu" signal "GND3")
		(20 "In9.Cu" signal "IN3")
		(22 "In10.Cu" signal "GND4")
		(24 "In11.Cu" signal "IN4")
		(26 "In12.Cu" signal "GND5")
		(28 "In13.Cu" signal "IN5")
		(30 "In14.Cu" signal "GND6")
		(32 "In15.Cu" signal "IN6")
		(34 "In16.Cu" signal "GND7")
		(2 "B.Cu" signal "BOTTOM")
		(9 "F.Adhes" user "F.Adhesive")
		(11 "B.Adhes" user "B.Adhesive")
		(13 "F.Paste" user "Package Geometry/Pastemask Top")
		(15 "B.Paste" user "Package Geometry/Pastemask Bottom")
		(5 "F.SilkS" user "Ref Des/Silkscreen Top")
		(7 "B.SilkS" user "Ref Des/Silkscreen Bottom")
		(1 "F.Mask" user "Board Geometry/Soldermask Top")
		(3 "B.Mask" user "Board Geometry/Soldermask Bottom")
		(17 "Dwgs.User" user "User.Drawings")
		(19 "Cmts.User" user "User.Comments")
		(21 "Eco1.User" user "User.Eco1")
		(23 "Eco2.User" user "User.Eco2")
		(25 "Edge.Cuts" user "Board Geometry/Outline")
		(27 "Margin" user)
		(31 "F.CrtYd" user "Package Geometry/Place Bound Top")
		(29 "B.CrtYd" user "Package Geometry/Place Bound Bottom")
		(35 "F.Fab" user "Ref Des/Assembly Top")
		(33 "B.Fab" user "Ref Des/Assembly Bottom")
	)
	(footprint ""
		(layer "F.Cu")
		(at 15.686786 -112.139476 -90)
		(property "Reference" "PR6915"
			(at 0 0 270)
			(layer "F.SilkS")
			(hide yes)
			(effects
				(font
					(size 1.27 1.27)
				)
			)
		)
		(property "Value" ""
			(at 0 0 270)
			(layer "F.Fab")
			(effects
				(font
					(size 1.27 1.27)
				)
			)
		)
		(duplicate_pad_numbers_are_jumpers no)
		(fp_line
			(start -0.7874 0.4064)
			(end -0.7874 -0.4064)
			(stroke
				(width 0.1524)
				(type default)
			)
			(layer "F.SilkS")
		)
		(fp_line
			(start 0.7874 0.4064)
			(end -0.7874 0.4064)
			(stroke
				(width 0.1524)
				(type default)
			)
			(layer "F.SilkS")
		)
		(fp_line
			(start -0.7874 -0.4064)
			(end 0.7874 -0.4064)
			(stroke
				(width 0.1524)
				(type default)
			)
			(layer "F.SilkS")
		)
		(fp_line
			(start 0.7874 -0.4064)
			(end 0.7874 0.4064)
			(stroke
				(width 0.1524)
				(type default)
			)
			(layer "F.SilkS")
		)
		(fp_line
			(start -0.67945 0.3048)
			(end -0.67945 -0.305054)
			(stroke
				(width 0.1)
				(type default)
			)
			(layer "F.Fab")
		)
		(fp_line
			(start -0.12065 0.3048)
			(end -0.67945 0.3048)
			(stroke
				(width 0.1)
				(type default)
			)
			(layer "F.Fab")
		)
		(fp_line
			(start 0.120396 0.3048)
			(end 0.120396 0.2794)
			(stroke
				(width 0.1)
				(type default)
			)
			(layer "F.Fab")
		)
		(fp_line
			(start 0.67945 0.3048)
			(end 0.120396 0.3048)
			(stroke
				(width 0.1)
				(type default)
			)
			(layer "F.Fab")
		)
		(fp_line
			(start -0.12065 0.2794)
			(end -0.12065 0.3048)
			(stroke
				(width 0.1)
				(type default)
			)
			(layer "F.Fab")
		)
		(fp_line
			(start 0.120396 0.2794)
			(end -0.12065 0.2794)
			(stroke
				(width 0.1)
				(type default)
			)
			(layer "F.Fab")
		)
		(fp_line
			(start -0.12065 -0.2794)
			(end 0.12065 -0.2794)
			(stroke
				(width 0.1)
				(type default)
			)
			(layer "F.Fab")
		)
		(fp_line
			(start 0.12065 -0.2794)
			(end 0.12065 -0.3048)
			(stroke
				(width 0.1)
				(type default)
			)
			(layer "F.Fab")
		)
		(fp_line
			(start 0.12065 -0.3048)
			(end 0.67945 -0.3048)
			(stroke
				(width 0.1)
				(type default)
			)
			(layer "F.Fab")
		)
		(fp_line
			(start 0.67945 -0.3048)
			(end 0.67945 0.3048)
			(stroke
				(width 0.1)
				(type default)
			)
			(layer "F.Fab")
		)
		(fp_line
			(start -0.67945 -0.305054)
			(end -0.12065 -0.305054)
			(stroke
				(width 0.1)
				(type default)
			)
			(layer "F.Fab")
		)
		(fp_line
			(start -0.12065 -0.305054)
			(end -0.12065 -0.2794)
			(stroke
				(width 0.1)
				(type default)
			)
			(layer "F.Fab")
		)
		(pad "1" smd circle
			(at -0.40005 0 270)
			(size 0 0)
			(layers "F.Cu" "F.Mask" "F.Paste")
			(net "P3V3_NIC0_CO_MODE")
		)
		(pad "2" smd circle
			(at 0.40005 0 270)
			(size 0 0)
			(layers "F.Cu" "F.Mask" "F.Paste")
			(net "GND")
		)
	)
	(footprint ""
		(layer "F.Cu")
		(at 111.668306 -230.949754 -90)
		(property "Reference" "PC1006"
			(at 0 0 270)
			(layer "F.SilkS")
			(hide yes)
			(effects
				(font
					(size 1.27 1.27)
				)
			)
		)
		(property "Value" ""
			(at 0 0 270)
			(layer "F.Fab")
			(effects
				(font
					(size 1.27 1.27)
				)
			)
		)
		(duplicate_pad_numbers_are_jumpers no)
		(fp_line
			(start -4.533392 2.249932)
			(end -4.533392 -2.249932)
			(stroke
				(width 0.1524)
				(type default)
			)
			(layer "F.SilkS")
		)
		(fp_line
			(start 4.533392 2.249932)
			(end -4.533392 2.249932)
			(stroke
				(width 0.1524)
				(type default)
			)
			(layer "F.SilkS")
		)
		(fp_line
			(start -4.533392 -2.249932)
			(end 4.533392 -2.249932)
			(stroke
				(width 0.1524)
				(type default)
			)
			(layer "F.SilkS")
		)
		(fp_line
			(start 4.533392 -2.249932)
			(end 4.533392 2.249932)
			(stroke
				(width 0.1524)
				(type default)
			)
			(layer "F.SilkS")
		)
		(fp_poly
			(pts
				(xy -4.533392 -2.326132) (xy -5.39242 -2.326132) (xy -5.39242 2.326132) (xy -4.533392 2.326132)
			)
			(stroke
				(width 0)
				(type default)
			)
			(fill yes)
			(layer "F.SilkS")
		)
		(fp_line
			(start -3.750056 2.249932)
			(end -3.750056 -2.249932)
			(stroke
				(width 0.1)
				(type default)
			)
			(layer "F.Fab")
		)
		(fp_line
			(start 3.750056 2.249932)
			(end -3.750056 2.249932)
			(stroke
				(width 0.1)
				(type default)
			)
			(layer "F.Fab")
		)
		(fp_line
			(start -3.750056 -2.249932)
			(end 3.750056 -2.249932)
			(stroke
				(width 0.1)
				(type default)
			)
			(layer "F.Fab")
		)
		(fp_line
			(start 3.750056 -2.249932)
			(end 3.750056 2.249932)
			(stroke
				(width 0.1)
				(type default)
			)
			(layer "F.Fab")
		)
		(fp_text user "+"
			(at -6.322314 0.786384 0)
			(unlocked yes)
			(layer "F.SilkS")
			(effects
				(font
					(size 1.905 1.4224)
					(thickness 0.1524)
				)
				(justify left)
			)
		)
		(fp_text user "-"
			(at 4.8514 -0.14605 270)
			(unlocked yes)
			(layer "F.SilkS")
			(effects
				(font
					(size 1.905 1.4224)
					(thickness 0.1524)
				)
				(justify left)
			)
		)
		(fp_text user "+"
			(at -6.322314 0.786384 0)
			(unlocked yes)
			(layer "F.Fab")
			(effects
				(font
					(size 1.905 1.4224)
					(thickness 0.1524)
				)
				(justify left)
			)
		)
		(fp_text user "-"
			(at 4.8514 -0.14605 270)
			(unlocked yes)
			(layer "F.Fab")
			(effects
				(font
					(size 1.905 1.4224)
					(thickness 0.1524)
				)
				(justify left)
			)
		)
		(pad "1" smd rect
			(at -3.199892 0 270)
			(size 2.413 2.8194)
			(layers "F.Cu" "F.Mask" "F.Paste")
			(net "P1V8_PEX_R")
		)
		(pad "2" smd rect
			(at 3.199892 0 270)
			(size 2.413 2.8194)
			(layers "F.Cu" "F.Mask" "F.Paste")
			(net "GND")
		)
	)
	(footprint ""
		(layer "F.Cu")
		(at 270.766286 -252.356874 -90)
		(property "Reference" "R1355"
			(at 0 0 270)
			(layer "F.SilkS")
			(hide yes)
			(effects
				(font
					(size 1.27 1.27)
				)
			)
		)
		(property "Value" ""
			(at 0 0 270)
			(layer "F.Fab")
			(effects
				(font
					(size 1.27 1.27)
				)
			)
		)
		(duplicate_pad_numbers_are_jumpers no)
		(fp_line
			(start -0.7874 0.4064)
			(end -0.7874 -0.4064)
			(stroke
				(width 0.1524)
				(type default)
			)
			(layer "F.SilkS")
		)
		(fp_line
			(start 0.7874 0.4064)
			(end -0.7874 0.4064)
			(stroke
				(width 0.1524)
				(type default)
			)
			(layer "F.SilkS")
		)
		(fp_line
			(start -0.7874 -0.4064)
			(end 0.7874 -0.4064)
			(stroke
				(width 0.1524)
				(type default)
			)
			(layer "F.SilkS")
		)
		(fp_line
			(start 0.7874 -0.4064)
			(end 0.7874 0.4064)
			(stroke
				(width 0.1524)
				(type default)
			)
			(layer "F.SilkS")
		)
		(fp_line
			(start -0.67945 0.3048)
			(end -0.67945 -0.305054)
			(stroke
				(width 0.1)
				(type default)
			)
			(layer "F.Fab")
		)
		(fp_line
			(start -0.12065 0.3048)
			(end -0.67945 0.3048)
			(stroke
				(width 0.1)
				(type default)
			)
			(layer "F.Fab")
		)
		(fp_line
			(start 0.120396 0.3048)
			(end 0.120396 0.2794)
			(stroke
				(width 0.1)
				(type default)
			)
			(layer "F.Fab")
		)
		(fp_line
			(start 0.67945 0.3048)
			(end 0.120396 0.3048)
			(stroke
				(width 0.1)
				(type default)
			)
			(layer "F.Fab")
		)
		(fp_line
			(start -0.12065 0.2794)
			(end -0.12065 0.3048)
			(stroke
				(width 0.1)
				(type default)
			)
			(layer "F.Fab")
		)
		(fp_line
			(start 0.120396 0.2794)
			(end -0.12065 0.2794)
			(stroke
				(width 0.1)
				(type default)
			)
			(layer "F.Fab")
		)
		(fp_line
			(start -0.12065 -0.2794)
			(end 0.12065 -0.2794)
			(stroke
				(width 0.1)
				(type default)
			)
			(layer "F.Fab")
		)
		(fp_line
			(start 0.12065 -0.2794)
			(end 0.12065 -0.3048)
			(stroke
				(width 0.1)
				(type default)
			)
			(layer "F.Fab")
		)
		(fp_line
			(start 0.12065 -0.3048)
			(end 0.67945 -0.3048)
			(stroke
				(width 0.1)
				(type default)
			)
			(layer "F.Fab")
		)
		(fp_line
			(start 0.67945 -0.3048)
			(end 0.67945 0.3048)
			(stroke
				(width 0.1)
				(type default)
			)
			(layer "F.Fab")
		)
		(fp_line
			(start -0.67945 -0.305054)
			(end -0.12065 -0.305054)
			(stroke
				(width 0.1)
				(type default)
			)
			(layer "F.Fab")
		)
		(fp_line
			(start -0.12065 -0.305054)
			(end -0.12065 -0.2794)
			(stroke
				(width 0.1)
				(type default)
			)
			(layer "F.Fab")
		)
		(pad "1" smd circle
			(at -0.40005 0 270)
			(size 0 0)
			(layers "F.Cu" "F.Mask" "F.Paste")
			(net "GND")
		)
		(pad "2" smd circle
			(at 0.40005 0 270)
			(size 0 0)
			(layers "F.Cu" "F.Mask" "F.Paste")
			(net "PEX2_DBG_MODE4")
		)
	)
	(footprint ""
		(layer "F.Cu")
		(at 428.957486 -112.504474 90)
		(property "Reference" "C950"
			(at 0 0 90)
			(layer "F.SilkS")
			(hide yes)
			(effects
				(font
					(size 1.27 1.27)
				)
			)
		)
		(property "Value" ""
			(at 0 0 90)
			(layer "F.Fab")
			(effects
				(font
					(size 1.27 1.27)
				)
			)
		)
		(duplicate_pad_numbers_are_jumpers no)
		(fp_line
			(start 1.524 -0.762)
			(end 1.524 0.762)
			(stroke
				(width 0.1524)
				(type default)
			)
			(layer "F.SilkS")
		)
		(fp_line
			(start -1.524 -0.762)
			(end 1.524 -0.762)
			(stroke
				(width 0.1524)
				(type default)
			)
			(layer "F.SilkS")
		)
		(fp_line
			(start 1.524 0.762)
			(end -1.524 0.762)
			(stroke
				(width 0.1524)
				(type default)
			)
			(layer "F.SilkS")
		)
		(fp_line
			(start -1.524 0.762)
			(end -1.524 -0.762)
			(stroke
				(width 0.1524)
				(type default)
			)
			(layer "F.SilkS")
		)
		(fp_line
			(start 1.1049 -0.724916)
			(end -1.1049 -0.724916)
			(stroke
				(width 0.1)
				(type default)
			)
			(layer "F.Fab")
		)
		(fp_line
			(start -1.1049 -0.724916)
			(end -1.1049 0.724916)
			(stroke
				(width 0.1)
				(type default)
			)
			(layer "F.Fab")
		)
		(fp_line
			(start 1.1049 0.724916)
			(end 1.1049 -0.724916)
			(stroke
				(width 0.1)
				(type default)
			)
			(layer "F.Fab")
		)
		(fp_line
			(start -1.1049 0.724916)
			(end 1.1049 0.724916)
			(stroke
				(width 0.1)
				(type default)
			)
			(layer "F.Fab")
		)
		(pad "1" smd rect
			(at -0.889 0 270)
			(size 1.016 1.27)
			(layers "F.Cu" "F.Mask" "F.Paste")
			(net "P12V_NIC7")
		)
		(pad "2" smd rect
			(at 0.889 0 270)
			(size 1.016 1.27)
			(layers "F.Cu" "F.Mask" "F.Paste")
			(net "GND")
		)
	)
	(footprint ""
		(layer "F.Cu")
		(at 213.630256 -233.830622 -90)
		(property "Reference" "R1549"
			(at 0 0 270)
			(layer "F.SilkS")
			(hide yes)
			(effects
				(font
					(size 1.27 1.27)
				)
			)
		)
		(property "Value" ""
			(at 0 0 270)
			(layer "F.Fab")
			(effects
				(font
					(size 1.27 1.27)
				)
			)
		)
		(duplicate_pad_numbers_are_jumpers no)
		(fp_line
			(start -0.7874 0.4064)
			(end -0.7874 -0.4064)
			(stroke
				(width 0.1524)
				(type default)
			)
			(layer "F.SilkS")
		)
		(fp_line
			(start 0.7874 0.4064)
			(end -0.7874 0.4064)
			(stroke
				(width 0.1524)
				(type default)
			)
			(layer "F.SilkS")
		)
		(fp_line
			(start -0.7874 -0.4064)
			(end 0.7874 -0.4064)
			(stroke
				(width 0.1524)
				(type default)
			)
			(layer "F.SilkS")
		)
		(fp_line
			(start 0.7874 -0.4064)
			(end 0.7874 0.4064)
			(stroke
				(width 0.1524)
				(type default)
			)
			(layer "F.SilkS")
		)
		(fp_line
			(start -0.67945 0.3048)
			(end -0.67945 -0.305054)
			(stroke
				(width 0.1)
				(type default)
			)
			(layer "F.Fab")
		)
		(fp_line
			(start -0.12065 0.3048)
			(end -0.67945 0.3048)
			(stroke
				(width 0.1)
				(type default)
			)
			(layer "F.Fab")
		)
		(fp_line
			(start 0.120396 0.3048)
			(end 0.120396 0.2794)
			(stroke
				(width 0.1)
				(type default)
			)
			(layer "F.Fab")
		)
		(fp_line
			(start 0.67945 0.3048)
			(end 0.120396 0.3048)
			(stroke
				(width 0.1)
				(type default)
			)
			(layer "F.Fab")
		)
		(fp_line
			(start -0.12065 0.2794)
			(end -0.12065 0.3048)
			(stroke
				(width 0.1)
				(type default)
			)
			(layer "F.Fab")
		)
		(fp_line
			(start 0.120396 0.2794)
			(end -0.12065 0.2794)
			(stroke
				(width 0.1)
				(type default)
			)
			(layer "F.Fab")
		)
		(fp_line
			(start -0.12065 -0.2794)
			(end 0.12065 -0.2794)
			(stroke
				(width 0.1)
				(type default)
			)
			(layer "F.Fab")
		)
		(fp_line
			(start 0.12065 -0.2794)
			(end 0.12065 -0.3048)
			(stroke
				(width 0.1)
				(type default)
			)
			(layer "F.Fab")
		)
		(fp_line
			(start 0.12065 -0.3048)
			(end 0.67945 -0.3048)
			(stroke
				(width 0.1)
				(type default)
			)
			(layer "F.Fab")
		)
		(fp_line
			(start 0.67945 -0.3048)
			(end 0.67945 0.3048)
			(stroke
				(width 0.1)
				(type default)
			)
			(layer "F.Fab")
		)
		(fp_line
			(start -0.67945 -0.305054)
			(end -0.12065 -0.305054)
			(stroke
				(width 0.1)
				(type default)
			)
			(layer "F.Fab")
		)
		(fp_line
			(start -0.12065 -0.305054)
			(end -0.12065 -0.2794)
			(stroke
				(width 0.1)
				(type default)
			)
			(layer "F.Fab")
		)
		(pad "1" smd circle
			(at -0.40005 0 270)
			(size 0 0)
			(layers "F.Cu" "F.Mask" "F.Paste")
			(net "SMB_PEX_LS_R_SCL")
		)
		(pad "2" smd circle
			(at 0.40005 0 270)
			(size 0 0)
			(layers "F.Cu" "F.Mask" "F.Paste")
			(net "SMB_PEX3_SCL")
		)
	)
	(footprint ""
		(layer "F.Cu")
		(at 175.415194 -20.72513)
		(property "Reference" "H119"
			(at 1.530604 -2.573528 0)
			(unlocked yes)
			(layer "B.SilkS")
			(effects
				(font
					(size 0.7874 0.5842)
					(thickness 0.1524)
				)
				(justify left mirror)
			)
		)
		(property "Value" ""
			(at 0 0 0)
			(layer "F.Fab")
			(effects
				(font
					(size 1.27 1.27)
				)
			)
		)
		(duplicate_pad_numbers_are_jumpers no)
		(pad "1" thru_hole rect
			(at 0 0)
			(size 4.2164 5.0038)
			(drill 2.0066
				(offset 0.099822 0)
			)
			(layers "*.Cu" "*.Mask")
			(remove_unused_layers no)
			(net "Net_8544")
			(clearance -0.8509)
			(padstack
				(mode front_inner_back)
				(layer "Inner"
					(shape circle)
					(size 4.0132 4.0132)
					(clearance -0.7493)
				)
				(layer "B.Cu"
					(shape circle)
					(size 4.0132 4.0132)
					(clearance -0.7493)
				)
			)
		)
	)
	(footprint ""
		(layer "F.Cu")
		(at 101.152198 -95.264224 90)
		(property "Reference" "R4448"
			(at 0 0 90)
			(layer "F.SilkS")
			(hide yes)
			(effects
				(font
					(size 1.27 1.27)
				)
			)
		)
		(property "Value" ""
			(at 0 0 90)
			(layer "F.Fab")
			(effects
				(font
					(size 1.27 1.27)
				)
			)
		)
		(duplicate_pad_numbers_are_jumpers no)
		(fp_line
			(start 0.7874 -0.4064)
			(end 0.7874 0.4064)
			(stroke
				(width 0.1524)
				(type default)
			)
			(layer "F.SilkS")
		)
		(fp_line
			(start -0.7874 -0.4064)
			(end 0.7874 -0.4064)
			(stroke
				(width 0.1524)
				(type default)
			)
			(layer "F.SilkS")
		)
		(fp_line
			(start 0.7874 0.4064)
			(end -0.7874 0.4064)
			(stroke
				(width 0.1524)
				(type default)
			)
			(layer "F.SilkS")
		)
		(fp_line
			(start -0.7874 0.4064)
			(end -0.7874 -0.4064)
			(stroke
				(width 0.1524)
				(type default)
			)
			(layer "F.SilkS")
		)
		(fp_line
			(start -0.12065 -0.305054)
			(end -0.12065 -0.2794)
			(stroke
				(width 0.1)
				(type default)
			)
			(layer "F.Fab")
		)
		(fp_line
			(start -0.67945 -0.305054)
			(end -0.12065 -0.305054)
			(stroke
				(width 0.1)
				(type default)
			)
			(layer "F.Fab")
		)
		(fp_line
			(start 0.67945 -0.3048)
			(end 0.67945 0.3048)
			(stroke
				(width 0.1)
				(type default)
			)
			(layer "F.Fab")
		)
		(fp_line
			(start 0.12065 -0.3048)
			(end 0.67945 -0.3048)
			(stroke
				(width 0.1)
				(type default)
			)
			(layer "F.Fab")
		)
		(fp_line
			(start 0.12065 -0.2794)
			(end 0.12065 -0.3048)
			(stroke
				(width 0.1)
				(type default)
			)
			(layer "F.Fab")
		)
		(fp_line
			(start -0.12065 -0.2794)
			(end 0.12065 -0.2794)
			(stroke
				(width 0.1)
				(type default)
			)
			(layer "F.Fab")
		)
		(fp_line
			(start 0.120396 0.2794)
			(end -0.12065 0.2794)
			(stroke
				(width 0.1)
				(type default)
			)
			(layer "F.Fab")
		)
		(fp_line
			(start -0.12065 0.2794)
			(end -0.12065 0.3048)
			(stroke
				(width 0.1)
				(type default)
			)
			(layer "F.Fab")
		)
		(fp_line
			(start 0.67945 0.3048)
			(end 0.120396 0.3048)
			(stroke
				(width 0.1)
				(type default)
			)
			(layer "F.Fab")
		)
		(fp_line
			(start 0.120396 0.3048)
			(end 0.120396 0.2794)
			(stroke
				(width 0.1)
				(type default)
			)
			(layer "F.Fab")
		)
		(fp_line
			(start -0.12065 0.3048)
			(end -0.67945 0.3048)
			(stroke
				(width 0.1)
				(type default)
			)
			(layer "F.Fab")
		)
		(fp_line
			(start -0.67945 0.3048)
			(end -0.67945 -0.305054)
			(stroke
				(width 0.1)
				(type default)
			)
			(layer "F.Fab")
		)
		(pad "1" smd circle
			(at -0.40005 0 90)
			(size 0 0)
			(layers "F.Cu" "F.Mask" "F.Paste")
			(net "HP_NIC1_EN")
		)
		(pad "2" smd circle
			(at 0.40005 0 90)
			(size 0 0)
			(layers "F.Cu" "F.Mask" "F.Paste")
			(net "P12V_NIC1_EN_R")
		)
	)
)
